(kicad_pcb
	(version 20260206)
	(generator "pcbnew")
	(generator_version "10.0")
	(general
		(thickness 1.6)
		(legacy_teardrops no)
	)
	(paper "A4")
	(title_block
		(title "v1-chassis-manager — T6M_CM_d_v01_1031_1645.brd")
		(comment 1 "Open CloudServer (Microsoft) / footprints 9-12 of 2512")
	)
	(layers
		(0 "F.Cu" signal "TOP")
		(4 "In1.Cu" signal "GND1")
		(6 "In2.Cu" signal "IN1")
		(8 "In3.Cu" signal "VCC1")
		(10 "In4.Cu" signal "VCC2")
		(12 "In5.Cu" signal "GND2")
		(14 "In6.Cu" signal "IN2")
		(16 "In7.Cu" signal "IN3")
		(18 "In8.Cu" signal "GND3")
		(2 "B.Cu" signal "BOTTOM")
		(9 "F.Adhes" user "F.Adhesive")
		(11 "B.Adhes" user "B.Adhesive")
		(13 "F.Paste" user "Package Geometry/Pastemask Top")
		(15 "B.Paste" user "Package Geometry/Pastemask Bottom")
		(5 "F.SilkS" user "Ref Des/Silkscreen Top")
		(7 "B.SilkS" user "Ref Des/Silkscreen Bottom")
		(1 "F.Mask" user "Board Geometry/Soldermask Top")
		(3 "B.Mask" user "Board Geometry/Soldermask Bottom")
		(17 "Dwgs.User" user "User.Drawings")
		(19 "Cmts.User" user "User.Comments")
		(21 "Eco1.User" user "User.Eco1")
		(23 "Eco2.User" user "User.Eco2")
		(25 "Edge.Cuts" user "Board Geometry/Outline")
		(27 "Margin" user)
		(31 "F.CrtYd" user "Package Geometry/Place Bound Top")
		(29 "B.CrtYd" user "Package Geometry/Place Bound Bottom")
		(35 "F.Fab" user "Ref Des/Assembly Top")
		(33 "B.Fab" user "Ref Des/Assembly Bottom")
	)
	(footprint ""
		(layer "F.Cu")
		(at 88.11641 -120.891554 -90)
		(property "Reference" "U115"
			(at 6.110986 5.566664 90)
			(unlocked yes)
			(layer "F.SilkS")
			(effects
				(font
					(size 0.7874 0.5842)
					(thickness 0.1524)
				)
				(justify left)
			)
		)
		(property "Value" ""
			(at 0 0 270)
			(layer "F.Fab")
			(effects
				(font
					(size 1.27 1.27)
				)
			)
		)
		(duplicate_pad_numbers_are_jumpers no)
		(fp_line
			(start -0.750062 5.1816)
			(end -0.750062 5.969)
			(stroke
				(width 0.1524)
				(type default)
			)
			(layer "F.SilkS")
		)
		(fp_line
			(start 1.75006 5.1816)
			(end 1.75006 6.5278)
			(stroke
				(width 0.1524)
				(type default)
			)
			(layer "F.SilkS")
		)
		(fp_line
			(start -2.794 3.429)
			(end 3.429 3.429)
			(stroke
				(width 0.1524)
				(type default)
			)
			(layer "F.SilkS")
		)
		(fp_line
			(start 3.429 3.429)
			(end 3.429 -3.429)
			(stroke
				(width 0.1524)
				(type default)
			)
			(layer "F.SilkS")
		)
		(fp_line
			(start -3.429 2.794)
			(end -2.794 3.429)
			(stroke
				(width 0.1524)
				(type default)
			)
			(layer "F.SilkS")
		)
		(fp_line
			(start 5.249926 1.7272)
			(end 6.249924 1.7272)
			(stroke
				(width 0.1524)
				(type default)
			)
			(layer "F.SilkS")
		)
		(fp_line
			(start -6.249924 1.2192)
			(end -5.249926 1.2192)
			(stroke
				(width 0.1524)
				(type default)
			)
			(layer "F.SilkS")
		)
		(fp_line
			(start 5.249926 -0.6858)
			(end 6.75005 -0.6858)
			(stroke
				(width 0.1524)
				(type default)
			)
			(layer "F.SilkS")
		)
		(fp_line
			(start -6.75005 -1.2192)
			(end -5.249926 -1.2192)
			(stroke
				(width 0.1524)
				(type default)
			)
			(layer "F.SilkS")
		)
		(fp_line
			(start -3.429 -3.429)
			(end -3.429 2.794)
			(stroke
				(width 0.1524)
				(type default)
			)
			(layer "F.SilkS")
		)
		(fp_line
			(start 3.429 -3.429)
			(end -3.429 -3.429)
			(stroke
				(width 0.1524)
				(type default)
			)
			(layer "F.SilkS")
		)
		(fp_line
			(start 0.249936 -5.1816)
			(end 0.249936 -6.3246)
			(stroke
				(width 0.1524)
				(type default)
			)
			(layer "F.SilkS")
		)
		(fp_line
			(start 2.750058 -5.1816)
			(end 2.750058 -5.8928)
			(stroke
				(width 0.1524)
				(type default)
			)
			(layer "F.SilkS")
		)
		(fp_line
			(start -2.249932 -5.207)
			(end -2.249932 -5.9182)
			(stroke
				(width 0.1524)
				(type default)
			)
			(layer "F.SilkS")
		)
		(fp_poly
			(pts
				(xy -3.127248 4.51993) (xy -4.448048 4.08813) (xy -4.448048 4.92633)
			)
			(stroke
				(width 0)
				(type default)
			)
			(fill yes)
			(layer "F.SilkS")
		)
		(fp_poly
			(pts
				(xy -2.921 5.0038) (xy -2.921 3.6068) (xy -3.6068 3.6068) (xy -3.6068 2.921) (xy -5.0038 2.921)
				(xy -5.0038 -2.921) (xy -3.6068 -2.921) (xy -3.6068 -3.6068) (xy -2.921 -3.6068) (xy -2.921 -5.0038)
				(xy 2.921 -5.0038) (xy 2.921 -3.6068) (xy 3.6068 -3.6068) (xy 3.6068 -2.921) (xy 5.0038 -2.921)
				(xy 5.0038 2.921) (xy 3.6068 2.921) (xy 3.6068 3.6068) (xy 2.921 3.6068) (xy 2.921 5.0038)
			)
			(stroke
				(width 0)
				(type default)
			)
			(fill no)
			(layer "F.CrtYd")
		)
		(fp_text user "12"
			(at 3.953764 4.94411 0)
			(unlocked yes)
			(layer "F.SilkS")
			(effects
				(font
					(size 0.7874 0.5842)
					(thickness 0.1524)
				)
				(justify left)
			)
		)
		(fp_text user "48"
			(at -5.197348 4.64947 0)
			(unlocked yes)
			(layer "F.SilkS")
			(effects
				(font
					(size 0.7874 0.5842)
					(thickness 0.1524)
				)
				(justify left)
			)
		)
		(fp_text user "13"
			(at 6.45414 3.56235 0)
			(unlocked yes)
			(layer "F.SilkS")
			(effects
				(font
					(size 0.7874 0.5842)
					(thickness 0.1524)
				)
				(justify left)
			)
		)
		(fp_text user "24"
			(at 5.349748 -3.109214 0)
			(unlocked yes)
			(layer "F.SilkS")
			(effects
				(font
					(size 0.7874 0.5842)
					(thickness 0.1524)
				)
				(justify left)
			)
		)
		(fp_text user "37"
			(at -3.771646 -4.138422 90)
			(unlocked yes)
			(layer "F.SilkS")
			(effects
				(font
					(size 0.7874 0.5842)
					(thickness 0.1524)
				)
				(justify left)
			)
		)
		(fp_text user "25"
			(at 4.545838 -4.76377 0)
			(unlocked yes)
			(layer "F.SilkS")
			(effects
				(font
					(size 0.7874 0.5842)
					(thickness 0.1524)
				)
				(justify left)
			)
		)
		(fp_text user "36"
			(at -2.588006 -5.626862 90)
			(unlocked yes)
			(layer "F.SilkS")
			(effects
				(font
					(size 0.7874 0.5842)
					(thickness 0.1524)
				)
				(justify left)
			)
		)
		(pad "1" smd rect
			(at -2.750058 4.299966 270)
			(size 0.2286 1.397)
			(layers "F.Cu" "F.Mask" "F.Paste")
			(net "N53313325")
		)
		(pad "2" smd rect
			(at -2.249932 4.299966 270)
			(size 0.2286 1.397)
			(layers "F.Cu" "F.Mask" "F.Paste")
			(net "PORT80_LOUT0")
		)
		(pad "3" smd rect
			(at -1.75006 4.299966 270)
			(size 0.2286 1.397)
			(layers "F.Cu" "F.Mask" "F.Paste")
			(net "LPC_CPU_NODE1_LAD3")
		)
		(pad "4" smd rect
			(at -1.249934 4.299966 270)
			(size 0.2286 1.397)
			(layers "F.Cu" "F.Mask" "F.Paste")
			(net "LPC_CPU_NODE1_LAD2")
		)
		(pad "5" smd rect
			(at -0.750062 4.299966 270)
			(size 0.2286 1.397)
			(layers "F.Cu" "F.Mask" "F.Paste")
			(net "GND")
		)
		(pad "6" smd rect
			(at -0.249936 4.299966 270)
			(size 0.2286 1.397)
			(layers "F.Cu" "F.Mask" "F.Paste")
			(net "P3V3_NODE1")
		)
		(pad "7" smd rect
			(at 0.249936 4.299966 270)
			(size 0.2286 1.397)
			(layers "F.Cu" "F.Mask" "F.Paste")
			(net "Net_2323")
		)
		(pad "8" smd rect
			(at 0.750062 4.299966 270)
			(size 0.2286 1.397)
			(layers "F.Cu" "F.Mask" "F.Paste")
			(net "Net_2322")
		)
		(pad "9" smd rect
			(at 1.249934 4.299966 270)
			(size 0.2286 1.397)
			(layers "F.Cu" "F.Mask" "F.Paste")
			(net "Net_2329")
		)
		(pad "10" smd rect
			(at 1.75006 4.299966 270)
			(size 0.2286 1.397)
			(layers "F.Cu" "F.Mask" "F.Paste")
			(net "Net_2328")
		)
		(pad "11" smd rect
			(at 2.249932 4.299966 270)
			(size 0.2286 1.397)
			(layers "F.Cu" "F.Mask" "F.Paste")
			(net "N53313175")
		)
		(pad "12" smd rect
			(at 2.750058 4.299966 270)
			(size 0.2286 1.397)
			(layers "F.Cu" "F.Mask" "F.Paste")
			(net "P3V3_NODE1")
		)
		(pad "13" smd rect
			(at 4.299966 2.750058 180)
			(size 0.2286 1.397)
			(layers "F.Cu" "F.Mask" "F.Paste")
			(net "GND")
		)
		(pad "14" smd rect
			(at 4.299966 2.249932 180)
			(size 0.2286 1.397)
			(layers "F.Cu" "F.Mask" "F.Paste")
			(net "Net_2327")
		)
		(pad "15" smd rect
			(at 4.299966 1.75006 180)
			(size 0.2286 1.397)
			(layers "F.Cu" "F.Mask" "F.Paste")
			(net "Net_2326")
		)
		(pad "16" smd rect
			(at 4.299966 1.249934 180)
			(size 0.2286 1.397)
			(layers "F.Cu" "F.Mask" "F.Paste")
			(net "Net_2325")
		)
		(pad "17" smd rect
			(at 4.299966 0.750062 180)
			(size 0.2286 1.397)
			(layers "F.Cu" "F.Mask" "F.Paste")
			(net "Net_2324")
		)
		(pad "18" smd rect
			(at 4.299966 0.249936 180)
			(size 0.2286 1.397)
			(layers "F.Cu" "F.Mask" "F.Paste")
			(net "FM_CPLD_NODE1_LPCRST_L")
		)
		(pad "19" smd rect
			(at 4.299966 -0.249936 180)
			(size 0.2286 1.397)
			(layers "F.Cu" "F.Mask" "F.Paste")
			(net "LPC_CPU_NODE1_LAD1")
		)
		(pad "20" smd rect
			(at 4.299966 -0.750062 180)
			(size 0.2286 1.397)
			(layers "F.Cu" "F.Mask" "F.Paste")
			(net "LPC_CPU_NODE1_FRAME_L")
		)
		(pad "21" smd rect
			(at 4.299966 -1.249934 180)
			(size 0.2286 1.397)
			(layers "F.Cu" "F.Mask" "F.Paste")
			(net "Net_2321")
		)
		(pad "22" smd rect
			(at 4.299966 -1.75006 180)
			(size 0.2286 1.397)
			(layers "F.Cu" "F.Mask" "F.Paste")
			(net "PORT80_LOUT6")
		)
		(pad "23" smd rect
			(at 4.299966 -2.249932 180)
			(size 0.2286 1.397)
			(layers "F.Cu" "F.Mask" "F.Paste")
			(net "Net_2314")
		)
		(pad "24" smd rect
			(at 4.299966 -2.750058 180)
			(size 0.2286 1.397)
			(layers "F.Cu" "F.Mask" "F.Paste")
			(net "Net_2313")
		)
		(pad "25" smd rect
			(at 2.750058 -4.299966 270)
			(size 0.2286 1.397)
			(layers "F.Cu" "F.Mask" "F.Paste")
			(net "N53313289")
		)
		(pad "26" smd rect
			(at 2.249932 -4.299966 270)
			(size 0.2286 1.397)
			(layers "F.Cu" "F.Mask" "F.Paste")
			(net "PORT80_LOUT5")
		)
		(pad "27" smd rect
			(at 1.75006 -4.299966 270)
			(size 0.2286 1.397)
			(layers "F.Cu" "F.Mask" "F.Paste")
			(net "Net_2312")
		)
		(pad "28" smd rect
			(at 1.249934 -4.299966 270)
			(size 0.2286 1.397)
			(layers "F.Cu" "F.Mask" "F.Paste")
			(net "Net_2311")
		)
		(pad "29" smd rect
			(at 0.750062 -4.299966 270)
			(size 0.2286 1.397)
			(layers "F.Cu" "F.Mask" "F.Paste")
			(net "GND")
		)
		(pad "30" smd rect
			(at 0.249936 -4.299966 270)
			(size 0.2286 1.397)
			(layers "F.Cu" "F.Mask" "F.Paste")
			(net "P3V3_NODE1")
		)
		(pad "31" smd rect
			(at -0.249936 -4.299966 270)
			(size 0.2286 1.397)
			(layers "F.Cu" "F.Mask" "F.Paste")
			(net "Net_2310")
		)
		(pad "32" smd rect
			(at -0.750062 -4.299966 270)
			(size 0.2286 1.397)
			(layers "F.Cu" "F.Mask" "F.Paste")
			(net "Net_2309")
		)
		(pad "33" smd rect
			(at -1.249934 -4.299966 270)
			(size 0.2286 1.397)
			(layers "F.Cu" "F.Mask" "F.Paste")
			(net "Net_2320")
		)
		(pad "34" smd rect
			(at -1.75006 -4.299966 270)
			(size 0.2286 1.397)
			(layers "F.Cu" "F.Mask" "F.Paste")
			(net "Net_2319")
		)
		(pad "35" smd rect
			(at -2.249932 -4.299966 270)
			(size 0.2286 1.397)
			(layers "F.Cu" "F.Mask" "F.Paste")
			(net "N53313389")
		)
		(pad "36" smd rect
			(at -2.750058 -4.299966 270)
			(size 0.2286 1.397)
			(layers "F.Cu" "F.Mask" "F.Paste")
			(net "P3V3_NODE1")
		)
		(pad "37" smd rect
			(at -4.299966 -2.750058)
			(size 0.2286 1.397)
			(layers "F.Cu" "F.Mask" "F.Paste")
			(net "GND")
		)
		(pad "38" smd rect
			(at -4.299966 -2.249932)
			(size 0.2286 1.397)
			(layers "F.Cu" "F.Mask" "F.Paste")
			(net "Net_2318")
		)
		(pad "39" smd rect
			(at -4.299966 -1.75006)
			(size 0.2286 1.397)
			(layers "F.Cu" "F.Mask" "F.Paste")
			(net "Net_2317")
		)
		(pad "40" smd rect
			(at -4.299966 -1.249934)
			(size 0.2286 1.397)
			(layers "F.Cu" "F.Mask" "F.Paste")
			(net "Net_2316")
		)
		(pad "41" smd rect
			(at -4.299966 -0.750062)
			(size 0.2286 1.397)
			(layers "F.Cu" "F.Mask" "F.Paste")
			(net "Net_2315")
		)
		(pad "42" smd rect
			(at -4.299966 -0.249936)
			(size 0.2286 1.397)
			(layers "F.Cu" "F.Mask" "F.Paste")
			(net "LPC_CPU_NODE1_LAD0")
		)
		(pad "43" smd rect
			(at -4.299966 0.249936)
			(size 0.2286 1.397)
			(layers "F.Cu" "F.Mask" "F.Paste")
			(net "CLK_33M_PORT80")
		)
		(pad "44" smd rect
			(at -4.299966 0.750062)
			(size 0.2286 1.397)
			(layers "F.Cu" "F.Mask" "F.Paste")
			(net "PORT80_LOUT7")
		)
		(pad "45" smd rect
			(at -4.299966 1.249934)
			(size 0.2286 1.397)
			(layers "F.Cu" "F.Mask" "F.Paste")
			(net "PORT80_LOUT4")
		)
		(pad "46" smd rect
			(at -4.299966 1.75006)
			(size 0.2286 1.397)
			(layers "F.Cu" "F.Mask" "F.Paste")
			(net "PORT80_LOUT3")
		)
		(pad "47" smd rect
			(at -4.299966 2.249932)
			(size 0.2286 1.397)
			(layers "F.Cu" "F.Mask" "F.Paste")
			(net "PORT80_LOUT2")
		)
		(pad "48" smd rect
			(at -4.299966 2.750058)
			(size 0.2286 1.397)
			(layers "F.Cu" "F.Mask" "F.Paste")
			(net "PORT80_LOUT1")
		)
	)
	(footprint ""
		(layer "F.Cu")
		(at 107.65663 -140.347192 90)
		(property "Reference" "PC111"
			(at 2.62636 4.345432 90)
			(unlocked yes)
			(layer "F.SilkS")
			(effects
				(font
					(size 0.635 0.4064)
					(thickness 0.1524)
				)
				(justify left)
			)
		)
		(property "Value" ""
			(at 0 0 90)
			(layer "F.Fab")
			(effects
				(font
					(size 1.27 1.27)
				)
			)
		)
		(duplicate_pad_numbers_are_jumpers no)
		(fp_line
			(start 0.7874 -0.4064)
			(end 0.7874 0.4064)
			(stroke
				(width 0.1524)
				(type default)
			)
			(layer "F.SilkS")
		)
		(fp_line
			(start -0.7874 -0.4064)
			(end 0.7874 -0.4064)
			(stroke
				(width 0.1524)
				(type default)
			)
			(layer "F.SilkS")
		)
		(fp_line
			(start 0 0.381)
			(end 0 -0.381)
			(stroke
				(width 0.1524)
				(type default)
			)
			(layer "F.SilkS")
		)
		(fp_line
			(start 0.7874 0.4064)
			(end -0.7874 0.4064)
			(stroke
				(width 0.1524)
				(type default)
			)
			(layer "F.SilkS")
		)
		(fp_line
			(start -0.7874 0.4064)
			(end -0.7874 -0.4064)
			(stroke
				(width 0.1524)
				(type default)
			)
			(layer "F.SilkS")
		)
		(fp_poly
			(pts
				(xy -0.5334 0.254) (xy -0.635 0.254) (xy -0.635 0.2286) (xy -0.635 -0.254) (xy -0.5334 -0.254) (xy -0.5334 -0.2794)
				(xy 0.5334 -0.2794) (xy 0.5334 -0.254) (xy 0.635 -0.254) (xy 0.635 0.254) (xy 0.5334 0.254) (xy 0.5334 0.2794)
				(xy -0.508 0.2794) (xy -0.5334 0.2794)
			)
			(stroke
				(width 0)
				(type default)
			)
			(fill no)
			(layer "F.CrtYd")
		)
		(pad "1" smd rect
			(at 0.40005 0 90)
			(size 0.4572 0.508)
			(layers "F.Cu" "F.Mask" "F.Paste")
			(net "AGND_PVCCP_NODE1")
		)
		(pad "2" smd rect
			(at -0.40005 0 90)
			(size 0.4572 0.508)
			(layers "F.Cu" "F.Mask" "F.Paste")
			(net "VR_PVCCP_NODE1_TSEN")
		)
	)
	(footprint ""
		(layer "F.Cu")
		(at 22.537166 -135.941308)
		(property "Reference" "C433"
			(at -0.675386 2.27076 0)
			(unlocked yes)
			(layer "F.SilkS")
			(effects
				(font
					(size 0.7874 0.5842)
					(thickness 0.1524)
				)
			)
		)
		(property "Value" ""
			(at 0 0 0)
			(layer "F.Fab")
			(effects
				(font
					(size 1.27 1.27)
				)
			)
		)
		(duplicate_pad_numbers_are_jumpers no)
		(fp_line
			(start -1.2954 -0.5842)
			(end 1.2954 -0.5842)
			(stroke
				(width 0.1524)
				(type default)
			)
			(layer "F.SilkS")
		)
		(fp_line
			(start -1.2954 0.5842)
			(end -1.2954 -0.5842)
			(stroke
				(width 0.1524)
				(type default)
			)
			(layer "F.SilkS")
		)
		(fp_line
			(start 0 -0.5842)
			(end 0 0.5842)
			(stroke
				(width 0.1524)
				(type default)
			)
			(layer "F.SilkS")
		)
		(fp_line
			(start 1.2954 -0.5842)
			(end 1.2954 0.5842)
			(stroke
				(width 0.1524)
				(type default)
			)
			(layer "F.SilkS")
		)
		(fp_line
			(start 1.2954 0.5842)
			(end -1.2954 0.5842)
			(stroke
				(width 0.1524)
				(type default)
			)
			(layer "F.SilkS")
		)
		(fp_poly
			(pts
				(xy 0.8636 -0.4572) (xy 0.8636 -0.3556) (xy 1.143 -0.3556) (xy 1.143 0.3556) (xy 0.8636 0.3556)
				(xy 0.8636 0.4572) (xy -0.8636 0.4572) (xy -0.8636 0.3556) (xy -1.143 0.3556) (xy -1.143 -0.3556)
				(xy -0.8636 -0.3556) (xy -0.8636 -0.4572)
			)
			(stroke
				(width 0)
				(type default)
			)
			(fill no)
			(layer "F.CrtYd")
		)
		(fp_line
			(start -0.884936 -0.504952)
			(end 0.884936 -0.504952)
			(stroke
				(width 0.1)
				(type default)
			)
			(layer "F.Fab")
		)
		(fp_line
			(start -0.884936 0.504952)
			(end -0.884936 -0.504952)
			(stroke
				(width 0.1)
				(type default)
			)
			(layer "F.Fab")
		)
		(fp_line
			(start 0.884936 -0.504952)
			(end 0.884936 0.504952)
			(stroke
				(width 0.1)
				(type default)
			)
			(layer "F.Fab")
		)
		(fp_line
			(start 0.884936 0.504952)
			(end -0.884936 0.504952)
			(stroke
				(width 0.1)
				(type default)
			)
			(layer "F.Fab")
		)
		(pad "1" smd rect
			(at 0.7366 0 90)
			(size 0.7112 0.8128)
			(layers "F.Cu" "F.Mask" "F.Paste")
			(net "P1V9_LAN1")
		)
		(pad "2" smd rect
			(at -0.7366 0 90)
			(size 0.7112 0.8128)
			(layers "F.Cu" "F.Mask" "F.Paste")
			(net "GND")
		)
	)
	(footprint ""
		(layer "F.Cu")
		(at 171.151042 -135.24738)
		(property "Reference" "R1122"
			(at -2.942082 -9.407398 0)
			(unlocked yes)
			(layer "F.SilkS")
			(effects
				(font
					(size 0.7874 0.5842)
					(thickness 0.1524)
				)
				(justify left)
			)
		)
		(property "Value" ""
			(at 0 0 0)
			(layer "F.Fab")
			(effects
				(font
					(size 1.27 1.27)
				)
			)
		)
		(duplicate_pad_numbers_are_jumpers no)
		(fp_line
			(start -0.7874 -0.4064)
			(end 0.7874 -0.4064)
			(stroke
				(width 0.1524)
				(type default)
			)
			(layer "F.SilkS")
		)
		(fp_line
			(start -0.7874 0.4064)
			(end -0.7874 -0.4064)
			(stroke
				(width 0.1524)
				(type default)
			)
			(layer "F.SilkS")
		)
		(fp_line
			(start 0.7874 -0.4064)
			(end 0.7874 0.4064)
			(stroke
				(width 0.1524)
				(type default)
			)
			(layer "F.SilkS")
		)
		(fp_line
			(start 0.7874 0.4064)
			(end -0.7874 0.4064)
			(stroke
				(width 0.1524)
				(type default)
			)
			(layer "F.SilkS")
		)
		(fp_poly
			(pts
				(xy -0.508 0.2794) (xy -0.508 0.2286) (xy -0.635 0.2286) (xy -0.635 -0.254) (xy -0.5334 -0.254)
				(xy -0.5334 -0.2794) (xy 0.5334 -0.2794) (xy 0.5334 -0.254) (xy 0.635 -0.254) (xy 0.635 0.254) (xy 0.5334 0.254)
				(xy 0.5334 0.2794)
			)
			(stroke
				(width 0)
				(type default)
			)
			(fill no)
			(layer "F.CrtYd")
		)
		(pad "1" smd rect
			(at 0.40005 0)
			(size 0.4572 0.508)
			(layers "F.Cu" "F.Mask" "F.Paste")
			(net "N41777080")
		)
		(pad "2" smd rect
			(at -0.40005 0)
			(size 0.4572 0.508)
			(layers "F.Cu" "F.Mask" "F.Paste")
			(net "P1V05_NODE1")
		)
	)
)
